(kicad_pcb
	(version 20260206)
	(generator "pcbnew")
	(generator_version "10.0")
	(general
		(thickness 1.6)
		(legacy_teardrops no)
	)
	(paper "A4")
	(title_block
		(title "Bryce Canyon_IOM_IOC_16318-2_OCP.brd")
		(comment 1 "Bryce Canyon / footprints 1494-1503 of 1605")
	)
	(layers
		(0 "F.Cu" signal "TOP")
		(4 "In1.Cu" signal "L2GND")
		(6 "In2.Cu" signal "L3")
		(8 "In3.Cu" signal "L4VCC")
		(10 "In4.Cu" signal "L5VCC")
		(12 "In5.Cu" signal "L6")
		(14 "In6.Cu" signal "L7GND")
		(2 "B.Cu" signal "BOTTOM")
		(9 "F.Adhes" user "F.Adhesive")
		(11 "B.Adhes" user "B.Adhesive")
		(13 "F.Paste" user "Package Geometry/Pastemask Top")
		(15 "B.Paste" user "Package Geometry/Pastemask Bottom")
		(5 "F.SilkS" user "Ref Des/Silkscreen Top")
		(7 "B.SilkS" user "Ref Des/Silkscreen Bottom")
		(1 "F.Mask" user "Board Geometry/Soldermask Top")
		(3 "B.Mask" user "Board Geometry/Soldermask Bottom")
		(17 "Dwgs.User" user "User.Drawings")
		(19 "Cmts.User" user "User.Comments")
		(21 "Eco1.User" user "User.Eco1")
		(23 "Eco2.User" user "User.Eco2")
		(25 "Edge.Cuts" user "Board Geometry/Outline")
		(27 "Margin" user)
		(31 "F.CrtYd" user "Package Geometry/Place Bound Top")
		(29 "B.CrtYd" user "Package Geometry/Place Bound Bottom")
		(35 "F.Fab" user "Ref Des/Assembly Top")
		(33 "B.Fab" user "Ref Des/Assembly Bottom")
	)
	(footprint ""
		(layer "B.Cu")
		(at 185.40222 -53.83276)
		(property "Reference" "TP166"
			(at 0 0 0)
			(layer "B.SilkS")
			(hide yes)
			(effects
				(font
					(size 1.27 1.27)
				)
				(justify mirror)
			)
		)
		(property "Value" "TPAD28-2-GP"
			(at 0.0127 -1.6637 0)
			(unlocked yes)
			(layer "B.Fab")
			(hide yes)
			(effects
				(font
					(size 1.016 1.016)
					(thickness 0.1524)
				)
				(justify mirror)
			)
		)
		(property "Device Type" "TPAD28"
			(at 0.0127 -3.1877 0)
			(unlocked yes)
			(layer "B.Fab")
			(hide yes)
			(effects
				(font
					(size 1.016 1.016)
					(thickness 0.1524)
				)
				(justify mirror)
			)
		)
		(duplicate_pad_numbers_are_jumpers no)
		(fp_poly
			(pts
				(arc
					(start 0.3556 0)
					(mid -0.3556 0)
					(end 0.3556 0)
				)
			)
			(stroke
				(width 0)
				(type default)
			)
			(fill no)
			(layer "B.CrtYd")
		)
		(fp_poly
			(pts
				(arc
					(start 0.6096 0)
					(mid -0.6096 0)
					(end 0.6096 0)
				)
			)
			(stroke
				(width 0)
				(type default)
			)
			(fill no)
			(layer "B.Fab")
		)
		(pad "1" smd circle
			(at 0 0 180)
			(size 0.7112 0.7112)
			(layers "B.Cu" "B.Mask" "B.Paste")
			(net "XM_CLE")
		)
	)
	(footprint ""
		(layer "B.Cu")
		(at 51.55438 -140.335 90)
		(property "Reference" "C999"
			(at 0 0 90)
			(layer "B.SilkS")
			(hide yes)
			(effects
				(font
					(size 1.27 1.27)
				)
				(justify mirror)
			)
		)
		(property "Value" "SCD1U16V2KX-3GP"
			(at -1.1811 -2.7051 90)
			(unlocked yes)
			(layer "B.Fab")
			(hide yes)
			(effects
				(font
					(size 1.016 1.016)
					(thickness 0.1524)
				)
				(justify mirror)
			)
		)
		(property "Device Type" "C402H22"
			(at -1.1811 -4.2291 90)
			(unlocked yes)
			(layer "B.Fab")
			(hide yes)
			(effects
				(font
					(size 1.016 1.016)
					(thickness 0.1524)
				)
				(justify mirror)
			)
		)
		(duplicate_pad_numbers_are_jumpers no)
		(fp_rect
			(start 0.4318 0.9525)
			(end -0.4318 -0.9525)
			(stroke
				(width 0)
				(type default)
			)
			(fill no)
			(layer "B.CrtYd")
		)
		(fp_rect
			(start 0.4318 0.9525)
			(end -0.4318 -0.9525)
			(stroke
				(width 0)
				(type default)
			)
			(fill no)
			(layer "B.Fab")
		)
		(pad "1" smd custom
			(at 0 -0.4445 270)
			(size 0.1524 0.1524)
			(layers "B.Cu" "B.Mask" "B.Paste")
			(net "P1V8_STBY")
			(options
				(clearance outline)
				(anchor circle)
			)
			(primitives
				(gr_poly
					(pts
						(arc
							(start 0.3048 0.2032)
							(mid 0.275042 0.275042)
							(end 0.2032 0.3048)
						)
						(arc
							(start -0.2032 0.3048)
							(mid -0.275042 0.275042)
							(end -0.3048 0.2032)
						)
						(arc
							(start -0.3048 -0.2032)
							(mid -0.275042 -0.275042)
							(end -0.2032 -0.3048)
						)
						(arc
							(start 0.2032 -0.3048)
							(mid 0.275042 -0.275042)
							(end 0.3048 -0.2032)
						)
					)
					(width 0)
					(fill yes)
				)
			)
		)
		(pad "2" smd custom
			(at 0 0.4445 270)
			(size 0.1524 0.1524)
			(layers "B.Cu" "B.Mask" "B.Paste")
			(net "GND")
			(options
				(clearance outline)
				(anchor circle)
			)
			(primitives
				(gr_poly
					(pts
						(arc
							(start 0.3048 0.2032)
							(mid 0.275042 0.275042)
							(end 0.2032 0.3048)
						)
						(arc
							(start -0.2032 0.3048)
							(mid -0.275042 0.275042)
							(end -0.3048 0.2032)
						)
						(arc
							(start -0.3048 -0.2032)
							(mid -0.275042 -0.275042)
							(end -0.2032 -0.3048)
						)
						(arc
							(start 0.2032 -0.3048)
							(mid 0.275042 -0.275042)
							(end 0.3048 -0.2032)
						)
					)
					(width 0)
					(fill yes)
				)
			)
		)
	)
	(footprint ""
		(layer "B.Cu")
		(at 68.792344 -142.956026)
		(property "Reference" "R194"
			(at 0 0 0)
			(layer "B.SilkS")
			(hide yes)
			(effects
				(font
					(size 1.27 1.27)
				)
				(justify mirror)
			)
		)
		(property "Value" "20KR2F-L-GP"
			(at -0.064008 -3.993896 0)
			(unlocked yes)
			(layer "B.Fab")
			(hide yes)
			(effects
				(font
					(size 1.016 1.016)
					(thickness 0.1524)
				)
				(justify mirror)
			)
		)
		(property "Device Type" "R402H16"
			(at -0.064008 -5.517896 0)
			(unlocked yes)
			(layer "B.Fab")
			(hide yes)
			(effects
				(font
					(size 1.016 1.016)
					(thickness 0.1524)
				)
				(justify mirror)
			)
		)
		(duplicate_pad_numbers_are_jumpers no)
		(fp_line
			(start -0.508 -0.9398)
			(end 0.508 -0.9398)
			(stroke
				(width 0.1524)
				(type default)
			)
			(layer "B.SilkS")
		)
		(fp_line
			(start 0.508 -0.9398)
			(end 0.508 0.9398)
			(stroke
				(width 0.1524)
				(type default)
			)
			(layer "B.SilkS")
		)
		(fp_rect
			(start 0.508 0.9398)
			(end -0.508 -0.9398)
			(stroke
				(width 0)
				(type default)
			)
			(fill no)
			(layer "B.CrtYd")
		)
		(fp_rect
			(start 0.508 0.9398)
			(end -0.508 -0.9398)
			(stroke
				(width 0)
				(type default)
			)
			(fill no)
			(layer "B.Fab")
		)
		(pad "1" smd custom
			(at 0 -0.4445 180)
			(size 0.1397 0.1397)
			(layers "B.Cu" "B.Mask" "B.Paste")
			(net "P3V3_STBY")
			(options
				(clearance outline)
				(anchor circle)
			)
			(primitives
				(gr_poly
					(pts
						(arc
							(start -0.1778 0.2794)
							(mid -0.249642 0.249642)
							(end -0.2794 0.1778)
						)
						(arc
							(start -0.2794 -0.1778)
							(mid -0.249642 -0.249642)
							(end -0.1778 -0.2794)
						)
						(arc
							(start 0.1778 -0.2794)
							(mid 0.249642 -0.249642)
							(end 0.2794 -0.1778)
						)
						(arc
							(start 0.2794 0.1778)
							(mid 0.249642 0.249642)
							(end 0.1778 0.2794)
						)
					)
					(width 0)
					(fill yes)
				)
			)
		)
		(pad "2" smd custom
			(at 0 0.4445 180)
			(size 0.1397 0.1397)
			(layers "B.Cu" "B.Mask" "B.Paste")
			(net "I2C_DEBUG_SDA_L")
			(options
				(clearance outline)
				(anchor circle)
			)
			(primitives
				(gr_poly
					(pts
						(arc
							(start -0.1778 0.2794)
							(mid -0.249642 0.249642)
							(end -0.2794 0.1778)
						)
						(arc
							(start -0.2794 -0.1778)
							(mid -0.249642 -0.249642)
							(end -0.1778 -0.2794)
						)
						(arc
							(start 0.1778 -0.2794)
							(mid 0.249642 -0.249642)
							(end 0.2794 -0.1778)
						)
						(arc
							(start 0.2794 0.1778)
							(mid 0.249642 0.249642)
							(end 0.1778 0.2794)
						)
					)
					(width 0)
					(fill yes)
				)
			)
		)
	)
	(footprint ""
		(layer "B.Cu")
		(at 40.350948 -155.983178)
		(property "Reference" "TP63"
			(at 0 0 0)
			(layer "B.SilkS")
			(hide yes)
			(effects
				(font
					(size 1.27 1.27)
				)
				(justify mirror)
			)
		)
		(property "Value" "TPAD28-2-GP"
			(at 0.0127 -1.6637 0)
			(unlocked yes)
			(layer "B.Fab")
			(hide yes)
			(effects
				(font
					(size 1.016 1.016)
					(thickness 0.1524)
				)
				(justify mirror)
			)
		)
		(property "Device Type" "TPAD28"
			(at 0.0127 -3.1877 0)
			(unlocked yes)
			(layer "B.Fab")
			(hide yes)
			(effects
				(font
					(size 1.016 1.016)
					(thickness 0.1524)
				)
				(justify mirror)
			)
		)
		(duplicate_pad_numbers_are_jumpers no)
		(fp_poly
			(pts
				(arc
					(start 0.3556 0)
					(mid -0.3556 0)
					(end 0.3556 0)
				)
			)
			(stroke
				(width 0)
				(type default)
			)
			(fill no)
			(layer "B.CrtYd")
		)
		(fp_poly
			(pts
				(arc
					(start 0.6096 0)
					(mid -0.6096 0)
					(end 0.6096 0)
				)
			)
			(stroke
				(width 0)
				(type default)
			)
			(fill no)
			(layer "B.Fab")
		)
		(pad "1" smd circle
			(at 0 0 180)
			(size 0.7112 0.7112)
			(layers "B.Cu" "B.Mask" "B.Paste")
			(net "TP_BMC_GPION3")
		)
	)
	(footprint ""
		(layer "B.Cu")
		(at 211.836 -86.106 90)
		(property "Reference" "C351"
			(at 0 0 90)
			(layer "B.SilkS")
			(hide yes)
			(effects
				(font
					(size 1.27 1.27)
				)
				(justify mirror)
			)
		)
		(property "Value" "SC10U6D3V5KX-4GP"
			(at 0.0762 -6.1214 90)
			(unlocked yes)
			(layer "B.Fab")
			(hide yes)
			(effects
				(font
					(size 1.016 1.016)
					(thickness 0.1524)
				)
				(justify mirror)
			)
		)
		(property "Device Type" "C805H58"
			(at 0.0762 -8.1534 90)
			(unlocked yes)
			(layer "B.Fab")
			(hide yes)
			(effects
				(font
					(size 1.016 1.016)
					(thickness 0.1524)
				)
				(justify mirror)
			)
		)
		(duplicate_pad_numbers_are_jumpers no)
		(fp_line
			(start -0.635 0)
			(end 0.635 0)
			(stroke
				(width 0.508)
				(type default)
			)
			(layer "B.SilkS")
		)
		(fp_rect
			(start 0.9652 1.778)
			(end -0.9652 -1.778)
			(stroke
				(width 0)
				(type default)
			)
			(fill no)
			(layer "B.CrtYd")
		)
		(fp_poly
			(pts
				(xy 0.9652 -1.778) (xy -0.9652 -1.778) (xy -0.9652 1.778) (xy 0.9652 1.778)
			)
			(stroke
				(width 0)
				(type default)
			)
			(fill no)
			(layer "B.Fab")
		)
		(pad "1" smd rect
			(at 0 -0.9652 270)
			(size 1.397 1.143)
			(layers "B.Cu" "B.Mask" "B.Paste")
			(net "SAS0_VDDH")
		)
		(pad "2" smd rect
			(at 0 0.9652 270)
			(size 1.397 1.143)
			(layers "B.Cu" "B.Mask" "B.Paste")
			(net "GND")
		)
	)
	(footprint ""
		(layer "B.Cu")
		(at 92.7862 -137.3124 -90)
		(property "Reference" "R275"
			(at 0 0 90)
			(layer "B.SilkS")
			(hide yes)
			(effects
				(font
					(size 1.27 1.27)
				)
				(justify mirror)
			)
		)
		(property "Value" "100KR2F-L1-GP"
			(at -0.064008 -3.993896 270)
			(unlocked yes)
			(layer "B.Fab")
			(hide yes)
			(effects
				(font
					(size 1.016 1.016)
					(thickness 0.1524)
				)
				(justify mirror)
			)
		)
		(property "Device Type" "R402H16"
			(at -0.064008 -5.517896 270)
			(unlocked yes)
			(layer "B.Fab")
			(hide yes)
			(effects
				(font
					(size 1.016 1.016)
					(thickness 0.1524)
				)
				(justify mirror)
			)
		)
		(duplicate_pad_numbers_are_jumpers no)
		(fp_line
			(start -0.508 -0.9398)
			(end 0.508 -0.9398)
			(stroke
				(width 0.1524)
				(type default)
			)
			(layer "B.SilkS")
		)
		(fp_line
			(start 0.508 -0.9398)
			(end 0.508 0.9398)
			(stroke
				(width 0.1524)
				(type default)
			)
			(layer "B.SilkS")
		)
		(fp_rect
			(start 0.508 0.9398)
			(end -0.508 -0.9398)
			(stroke
				(width 0)
				(type default)
			)
			(fill no)
			(layer "B.CrtYd")
		)
		(fp_rect
			(start 0.508 0.9398)
			(end -0.508 -0.9398)
			(stroke
				(width 0)
				(type default)
			)
			(fill no)
			(layer "B.Fab")
		)
		(pad "1" smd custom
			(at 0 -0.4445 90)
			(size 0.1397 0.1397)
			(layers "B.Cu" "B.Mask" "B.Paste")
			(net "DEBUG_CARD_PRSNT")
			(options
				(clearance outline)
				(anchor circle)
			)
			(primitives
				(gr_poly
					(pts
						(arc
							(start -0.1778 0.2794)
							(mid -0.249642 0.249642)
							(end -0.2794 0.1778)
						)
						(arc
							(start -0.2794 -0.1778)
							(mid -0.249642 -0.249642)
							(end -0.1778 -0.2794)
						)
						(arc
							(start 0.1778 -0.2794)
							(mid 0.249642 -0.249642)
							(end 0.2794 -0.1778)
						)
						(arc
							(start 0.2794 0.1778)
							(mid 0.249642 0.249642)
							(end 0.1778 0.2794)
						)
					)
					(width 0)
					(fill yes)
				)
			)
		)
		(pad "2" smd custom
			(at 0 0.4445 90)
			(size 0.1397 0.1397)
			(layers "B.Cu" "B.Mask" "B.Paste")
			(net "GND")
			(options
				(clearance outline)
				(anchor circle)
			)
			(primitives
				(gr_poly
					(pts
						(arc
							(start -0.1778 0.2794)
							(mid -0.249642 0.249642)
							(end -0.2794 0.1778)
						)
						(arc
							(start -0.2794 -0.1778)
							(mid -0.249642 -0.249642)
							(end -0.1778 -0.2794)
						)
						(arc
							(start 0.1778 -0.2794)
							(mid 0.249642 -0.249642)
							(end 0.2794 -0.1778)
						)
						(arc
							(start 0.2794 0.1778)
							(mid 0.249642 0.249642)
							(end 0.1778 0.2794)
						)
					)
					(width 0)
					(fill yes)
				)
			)
		)
	)
	(footprint ""
		(layer "B.Cu")
		(at 183.48706 -81.49844)
		(property "Reference" "C393"
			(at 0 0 0)
			(layer "B.SilkS")
			(hide yes)
			(effects
				(font
					(size 1.27 1.27)
				)
				(justify mirror)
			)
		)
		(property "Value" "SC1U16V2KX-7-GP"
			(at -1.7526 -1.6002 0)
			(unlocked yes)
			(layer "B.Fab")
			(hide yes)
			(effects
				(font
					(size 1.016 1.016)
					(thickness 0.1524)
				)
				(justify mirror)
			)
		)
		(property "Device Type" "C402-TO0D2H24"
			(at -1.7526 -3.1242 0)
			(unlocked yes)
			(layer "B.Fab")
			(hide yes)
			(effects
				(font
					(size 1.016 1.016)
					(thickness 0.1524)
				)
				(justify mirror)
			)
		)
		(duplicate_pad_numbers_are_jumpers no)
		(fp_rect
			(start 0.4826 0.889)
			(end -0.4826 -0.889)
			(stroke
				(width 0)
				(type default)
			)
			(fill no)
			(layer "B.CrtYd")
		)
		(fp_rect
			(start 0.4826 0.889)
			(end -0.4826 -0.889)
			(stroke
				(width 0)
				(type default)
			)
			(fill no)
			(layer "B.Fab")
		)
		(pad "1" smd custom
			(at 0 -0.4572 180)
			(size 0.1524 0.1524)
			(layers "B.Cu" "B.Mask" "B.Paste")
			(net "P0V975")
			(options
				(clearance outline)
				(anchor circle)
			)
			(primitives
				(gr_poly
					(pts
						(arc
							(start -0.254 -0.3048)
							(mid -0.325842 -0.275042)
							(end -0.3556 -0.2032)
						)
						(arc
							(start -0.3556 0.2032)
							(mid -0.325842 0.275042)
							(end -0.254 0.3048)
						)
						(arc
							(start 0.254 0.3048)
							(mid 0.325842 0.275042)
							(end 0.3556 0.2032)
						)
						(arc
							(start 0.3556 -0.2032)
							(mid 0.325842 -0.275042)
							(end 0.254 -0.3048)
						)
					)
					(width 0)
					(fill yes)
				)
			)
		)
		(pad "2" smd custom
			(at 0 0.4572 180)
			(size 0.1524 0.1524)
			(layers "B.Cu" "B.Mask" "B.Paste")
			(net "GND")
			(options
				(clearance outline)
				(anchor circle)
			)
			(primitives
				(gr_poly
					(pts
						(arc
							(start -0.254 -0.3048)
							(mid -0.325842 -0.275042)
							(end -0.3556 -0.2032)
						)
						(arc
							(start -0.3556 0.2032)
							(mid -0.325842 0.275042)
							(end -0.254 0.3048)
						)
						(arc
							(start 0.254 0.3048)
							(mid 0.325842 0.275042)
							(end 0.3556 0.2032)
						)
						(arc
							(start 0.3556 -0.2032)
							(mid 0.325842 -0.275042)
							(end 0.254 -0.3048)
						)
					)
					(width 0)
					(fill yes)
				)
			)
		)
	)
	(footprint ""
		(layer "B.Cu")
		(at 180.675788 -74.726546)
		(property "Reference" "TP112"
			(at 0 0 0)
			(layer "B.SilkS")
			(hide yes)
			(effects
				(font
					(size 1.27 1.27)
				)
				(justify mirror)
			)
		)
		(property "Value" "TPAD28-2-GP"
			(at 0.0127 -1.6637 0)
			(unlocked yes)
			(layer "B.Fab")
			(hide yes)
			(effects
				(font
					(size 1.016 1.016)
					(thickness 0.1524)
				)
				(justify mirror)
			)
		)
		(property "Device Type" "TPAD28"
			(at 0.0127 -3.1877 0)
			(unlocked yes)
			(layer "B.Fab")
			(hide yes)
			(effects
				(font
					(size 1.016 1.016)
					(thickness 0.1524)
				)
				(justify mirror)
			)
		)
		(duplicate_pad_numbers_are_jumpers no)
		(fp_poly
			(pts
				(arc
					(start 0.3556 0)
					(mid -0.3556 0)
					(end 0.3556 0)
				)
			)
			(stroke
				(width 0)
				(type default)
			)
			(fill no)
			(layer "B.CrtYd")
		)
		(fp_poly
			(pts
				(arc
					(start 0.6096 0)
					(mid -0.6096 0)
					(end 0.6096 0)
				)
			)
			(stroke
				(width 0)
				(type default)
			)
			(fill no)
			(layer "B.Fab")
		)
		(pad "1" smd circle
			(at 0 0 180)
			(size 0.7112 0.7112)
			(layers "B.Cu" "B.Mask" "B.Paste")
			(net "IOC_GPIO_26")
		)
	)
	(footprint ""
		(layer "B.Cu")
		(at 111.6838 -9.6012 90)
		(property "Reference" "R461"
			(at 0 0 90)
			(layer "B.SilkS")
			(hide yes)
			(effects
				(font
					(size 1.27 1.27)
				)
				(justify mirror)
			)
		)
		(property "Value" "100KR2J-4-GP"
			(at -0.064008 -3.993896 90)
			(unlocked yes)
			(layer "B.Fab")
			(hide yes)
			(effects
				(font
					(size 1.016 1.016)
					(thickness 0.1524)
				)
				(justify mirror)
			)
		)
		(property "Device Type" "R402H15"
			(at -0.064008 -5.517896 90)
			(unlocked yes)
			(layer "B.Fab")
			(hide yes)
			(effects
				(font
					(size 1.016 1.016)
					(thickness 0.1524)
				)
				(justify mirror)
			)
		)
		(duplicate_pad_numbers_are_jumpers no)
		(fp_line
			(start 0.508 -0.9398)
			(end 0.508 0.9398)
			(stroke
				(width 0.1524)
				(type default)
			)
			(layer "B.SilkS")
		)
		(fp_line
			(start -0.508 -0.9398)
			(end 0.508 -0.9398)
			(stroke
				(width 0.1524)
				(type default)
			)
			(layer "B.SilkS")
		)
		(fp_rect
			(start 0.508 0.9398)
			(end -0.508 -0.9398)
			(stroke
				(width 0)
				(type default)
			)
			(fill no)
			(layer "B.CrtYd")
		)
		(fp_rect
			(start 0.508 0.9398)
			(end -0.508 -0.9398)
			(stroke
				(width 0)
				(type default)
			)
			(fill no)
			(layer "B.Fab")
		)
		(pad "1" smd custom
			(at 0 -0.4445 270)
			(size 0.1397 0.1397)
			(layers "B.Cu" "B.Mask" "B.Paste")
			(net "MB0_VCAP_R")
			(options
				(clearance outline)
				(anchor circle)
			)
			(primitives
				(gr_poly
					(pts
						(arc
							(start -0.1778 0.2794)
							(mid -0.249642 0.249642)
							(end -0.2794 0.1778)
						)
						(arc
							(start -0.2794 -0.1778)
							(mid -0.249642 -0.249642)
							(end -0.1778 -0.2794)
						)
						(arc
							(start 0.1778 -0.2794)
							(mid 0.249642 -0.249642)
							(end 0.2794 -0.1778)
						)
						(arc
							(start 0.2794 0.1778)
							(mid 0.249642 0.249642)
							(end 0.1778 0.2794)
						)
					)
					(width 0)
					(fill yes)
				)
			)
		)
		(pad "2" smd custom
			(at 0 0.4445 270)
			(size 0.1397 0.1397)
			(layers "B.Cu" "B.Mask" "B.Paste")
			(net "MB0_ISTART_R")
			(options
				(clearance outline)
				(anchor circle)
			)
			(primitives
				(gr_poly
					(pts
						(arc
							(start -0.1778 0.2794)
							(mid -0.249642 0.249642)
							(end -0.2794 0.1778)
						)
						(arc
							(start -0.2794 -0.1778)
							(mid -0.249642 -0.249642)
							(end -0.1778 -0.2794)
						)
						(arc
							(start 0.1778 -0.2794)
							(mid 0.249642 -0.249642)
							(end 0.2794 -0.1778)
						)
						(arc
							(start 0.2794 0.1778)
							(mid 0.249642 0.249642)
							(end 0.1778 0.2794)
						)
					)
					(width 0)
					(fill yes)
				)
			)
		)
	)
	(footprint ""
		(layer "B.Cu")
		(at 186.7916 -66.3321 -90)
		(property "Reference" "C387"
			(at 0 0 90)
			(layer "B.SilkS")
			(hide yes)
			(effects
				(font
					(size 1.27 1.27)
				)
				(justify mirror)
			)
		)
		(property "Value" "SC10U6D3V5KX-4GP"
			(at 0.0762 -6.1214 270)
			(unlocked yes)
			(layer "B.Fab")
			(hide yes)
			(effects
				(font
					(size 1.016 1.016)
					(thickness 0.1524)
				)
				(justify mirror)
			)
		)
		(property "Device Type" "C805H58"
			(at 0.0762 -8.1534 270)
			(unlocked yes)
			(layer "B.Fab")
			(hide yes)
			(effects
				(font
					(size 1.016 1.016)
					(thickness 0.1524)
				)
				(justify mirror)
			)
		)
		(duplicate_pad_numbers_are_jumpers no)
		(fp_line
			(start -0.635 0)
			(end 0.635 0)
			(stroke
				(width 0.508)
				(type default)
			)
			(layer "B.SilkS")
		)
		(fp_rect
			(start 0.9652 1.778)
			(end -0.9652 -1.778)
			(stroke
				(width 0)
				(type default)
			)
			(fill no)
			(layer "B.CrtYd")
		)
		(fp_poly
			(pts
				(xy 0.9652 -1.778) (xy -0.9652 -1.778) (xy -0.9652 1.778) (xy 0.9652 1.778)
			)
			(stroke
				(width 0)
				(type default)
			)
			(fill no)
			(layer "B.Fab")
		)
		(pad "1" smd rect
			(at 0 -0.9652 90)
			(size 1.397 1.143)
			(layers "B.Cu" "B.Mask" "B.Paste")
			(net "P0V975")
		)
		(pad "2" smd rect
			(at 0 0.9652 90)
			(size 1.397 1.143)
			(layers "B.Cu" "B.Mask" "B.Paste")
			(net "GND")
		)
	)
)
